# T6G (Grand Teton) — schematic netlist excerpt (pin names and nets, part order shuffled) for the footprints in the layout excerpt that follows; sources: Cadence DE-HDL packaged netlist, KiCad conversion of 04192023_DAF0TMB3IC0_F0TG_MB_C_brd_V02_OCP.brd

R1304  Q_RES  10K 1% CHIP  pkg 0402LF  page 83 : A = E1S_0_PRSNT_N ; B = P3V3_AUX
R3511  Q_RES  54.9K 1% CHIP  pkg 0402LF  page 127 : A = GPU_FPGA_READY ; B = GND

(kicad_pcb
	(version 20260206)
	(generator "pcbnew")
	(generator_version "10.0")
	(general
		(thickness 1.6)
		(legacy_teardrops no)
	)
	(paper "A4")
	(title_block
		(title "04192023_DAF0TMB3IC0_F0TG_MB_C_brd_V02_OCP.brd")
		(comment 1 "Grand Teton / footprints 5692-5693 of 8354")
	)
	(layers
		(0 "F.Cu" signal "TOP")
		(4 "In1.Cu" signal "GND")
		(6 "In2.Cu" signal "IN1")
		(8 "In3.Cu" signal "GND1")
		(10 "In4.Cu" signal "IN2")
		(12 "In5.Cu" signal "GND2")
		(14 "In6.Cu" signal "IN3")
		(16 "In7.Cu" signal "GND3")
		(18 "In8.Cu" signal "VCC")
		(20 "In9.Cu" signal "VCC1")
		(22 "In10.Cu" signal "GND4")
		(24 "In11.Cu" signal "IN4")
		(26 "In12.Cu" signal "GND5")
		(28 "In13.Cu" signal "IN5")
		(30 "In14.Cu" signal "GND6")
		(32 "In15.Cu" signal "IN6")
		(34 "In16.Cu" signal "GND7")
		(2 "B.Cu" signal "BOTTOM")
		(9 "F.Adhes" user "F.Adhesive")
		(11 "B.Adhes" user "B.Adhesive")
		(13 "F.Paste" user "Package Geometry/Pastemask Top")
		(15 "B.Paste" user "Package Geometry/Pastemask Bottom")
		(5 "F.SilkS" user "Ref Des/Silkscreen Top")
		(7 "B.SilkS" user "Ref Des/Silkscreen Bottom")
		(1 "F.Mask" user "Board Geometry/Soldermask Top")
		(3 "B.Mask" user "Board Geometry/Soldermask Bottom")
		(17 "Dwgs.User" user "User.Drawings")
		(19 "Cmts.User" user "User.Comments")
		(21 "Eco1.User" user "User.Eco1")
		(23 "Eco2.User" user "User.Eco2")
		(25 "Edge.Cuts" user "Board Geometry/Outline")
		(27 "Margin" user)
		(31 "F.CrtYd" user "Package Geometry/Place Bound Top")
		(29 "B.CrtYd" user "Package Geometry/Place Bound Bottom")
		(35 "F.Fab" user "Ref Des/Assembly Top")
		(33 "B.Fab" user "Ref Des/Assembly Bottom")
	)
	(footprint ""
		(layer "B.Cu")
		(at 193.929 -100.294948 90)
		(property "Reference" "R1304"
			(at 0 0 90)
			(layer "B.SilkS")
			(hide yes)
			(effects
				(font
					(size 1.27 1.27)
				)
				(justify mirror)
			)
		)
		(property "Value" ""
			(at 0 0 90)
			(layer "B.Fab")
			(effects
				(font
					(size 1.27 1.27)
				)
				(justify mirror)
			)
		)
		(duplicate_pad_numbers_are_jumpers no)
		(fp_line
			(start 0.7874 -0.4064)
			(end -0.7874 -0.4064)
			(stroke
				(width 0.1524)
				(type default)
			)
			(layer "B.SilkS")
		)
		(fp_line
			(start -0.7874 -0.4064)
			(end -0.7874 0.4064)
			(stroke
				(width 0.1524)
				(type default)
			)
			(layer "B.SilkS")
		)
		(fp_line
			(start 0.7874 0.4064)
			(end 0.7874 -0.4064)
			(stroke
				(width 0.1524)
				(type default)
			)
			(layer "B.SilkS")
		)
		(fp_line
			(start -0.7874 0.4064)
			(end 0.7874 0.4064)
			(stroke
				(width 0.1524)
				(type default)
			)
			(layer "B.SilkS")
		)
		(fp_line
			(start 0.67945 -0.305054)
			(end 0.12065 -0.305054)
			(stroke
				(width 0.1)
				(type default)
			)
			(layer "B.Fab")
		)
		(fp_line
			(start 0.12065 -0.305054)
			(end 0.12065 -0.2794)
			(stroke
				(width 0.1)
				(type default)
			)
			(layer "B.Fab")
		)
		(fp_line
			(start -0.12065 -0.3048)
			(end -0.67945 -0.3048)
			(stroke
				(width 0.1)
				(type default)
			)
			(layer "B.Fab")
		)
		(fp_line
			(start -0.67945 -0.3048)
			(end -0.67945 0.3048)
			(stroke
				(width 0.1)
				(type default)
			)
			(layer "B.Fab")
		)
		(fp_line
			(start 0.12065 -0.2794)
			(end -0.12065 -0.2794)
			(stroke
				(width 0.1)
				(type default)
			)
			(layer "B.Fab")
		)
		(fp_line
			(start -0.12065 -0.2794)
			(end -0.12065 -0.3048)
			(stroke
				(width 0.1)
				(type default)
			)
			(layer "B.Fab")
		)
		(fp_line
			(start 0.12065 0.2794)
			(end 0.12065 0.3048)
			(stroke
				(width 0.1)
				(type default)
			)
			(layer "B.Fab")
		)
		(fp_line
			(start -0.120396 0.2794)
			(end 0.12065 0.2794)
			(stroke
				(width 0.1)
				(type default)
			)
			(layer "B.Fab")
		)
		(fp_line
			(start 0.67945 0.3048)
			(end 0.67945 -0.305054)
			(stroke
				(width 0.1)
				(type default)
			)
			(layer "B.Fab")
		)
		(fp_line
			(start 0.12065 0.3048)
			(end 0.67945 0.3048)
			(stroke
				(width 0.1)
				(type default)
			)
			(layer "B.Fab")
		)
		(fp_line
			(start -0.120396 0.3048)
			(end -0.120396 0.2794)
			(stroke
				(width 0.1)
				(type default)
			)
			(layer "B.Fab")
		)
		(fp_line
			(start -0.67945 0.3048)
			(end -0.120396 0.3048)
			(stroke
				(width 0.1)
				(type default)
			)
			(layer "B.Fab")
		)
		(pad "1" smd circle
			(at 0.40005 0 270)
			(size 0 0)
			(layers "B.Cu" "B.Mask" "B.Paste")
			(net "E1S_0_PRSNT_N")
		)
		(pad "2" smd circle
			(at -0.40005 0 270)
			(size 0 0)
			(layers "B.Cu" "B.Mask" "B.Paste")
			(net "P3V3_AUX")
		)
	)
	(footprint ""
		(layer "B.Cu")
		(at 51.328574 -422.777666)
		(property "Reference" "R3511"
			(at 0 0 0)
			(layer "B.SilkS")
			(hide yes)
			(effects
				(font
					(size 1.27 1.27)
				)
				(justify mirror)
			)
		)
		(property "Value" ""
			(at 0 0 0)
			(layer "B.Fab")
			(effects
				(font
					(size 1.27 1.27)
				)
				(justify mirror)
			)
		)
		(duplicate_pad_numbers_are_jumpers no)
		(fp_line
			(start -0.7874 -0.4064)
			(end -0.7874 0.4064)
			(stroke
				(width 0.1524)
				(type default)
			)
			(layer "B.SilkS")
		)
		(fp_line
			(start -0.7874 0.4064)
			(end 0.7874 0.4064)
			(stroke
				(width 0.1524)
				(type default)
			)
			(layer "B.SilkS")
		)
		(fp_line
			(start 0.7874 -0.4064)
			(end -0.7874 -0.4064)
			(stroke
				(width 0.1524)
				(type default)
			)
			(layer "B.SilkS")
		)
		(fp_line
			(start 0.7874 0.4064)
			(end 0.7874 -0.4064)
			(stroke
				(width 0.1524)
				(type default)
			)
			(layer "B.SilkS")
		)
		(fp_line
			(start -0.67945 -0.3048)
			(end -0.67945 0.3048)
			(stroke
				(width 0.1)
				(type default)
			)
			(layer "B.Fab")
		)
		(fp_line
			(start -0.67945 0.3048)
			(end -0.120396 0.3048)
			(stroke
				(width 0.1)
				(type default)
			)
			(layer "B.Fab")
		)
		(fp_line
			(start -0.12065 -0.3048)
			(end -0.67945 -0.3048)
			(stroke
				(width 0.1)
				(type default)
			)
			(layer "B.Fab")
		)
		(fp_line
			(start -0.12065 -0.2794)
			(end -0.12065 -0.3048)
			(stroke
				(width 0.1)
				(type default)
			)
			(layer "B.Fab")
		)
		(fp_line
			(start -0.120396 0.2794)
			(end 0.12065 0.2794)
			(stroke
				(width 0.1)
				(type default)
			)
			(layer "B.Fab")
		)
		(fp_line
			(start -0.120396 0.3048)
			(end -0.120396 0.2794)
			(stroke
				(width 0.1)
				(type default)
			)
			(layer "B.Fab")
		)
		(fp_line
			(start 0.12065 -0.305054)
			(end 0.12065 -0.2794)
			(stroke
				(width 0.1)
				(type default)
			)
			(layer "B.Fab")
		)
		(fp_line
			(start 0.12065 -0.2794)
			(end -0.12065 -0.2794)
			(stroke
				(width 0.1)
				(type default)
			)
			(layer "B.Fab")
		)
		(fp_line
			(start 0.12065 0.2794)
			(end 0.12065 0.3048)
			(stroke
				(width 0.1)
				(type default)
			)
			(layer "B.Fab")
		)
		(fp_line
			(start 0.12065 0.3048)
			(end 0.67945 0.3048)
			(stroke
				(width 0.1)
				(type default)
			)
			(layer "B.Fab")
		)
		(fp_line
			(start 0.67945 -0.305054)
			(end 0.12065 -0.305054)
			(stroke
				(width 0.1)
				(type default)
			)
			(layer "B.Fab")
		)
		(fp_line
			(start 0.67945 0.3048)
			(end 0.67945 -0.305054)
			(stroke
				(width 0.1)
				(type default)
			)
			(layer "B.Fab")
		)
		(pad "1" smd circle
			(at 0.40005 0 180)
			(size 0 0)
			(layers "B.Cu" "B.Mask" "B.Paste")
			(net "GPU_FPGA_READY")
		)
		(pad "2" smd circle
			(at -0.40005 0 180)
			(size 0 0)
			(layers "B.Cu" "B.Mask" "B.Paste")
			(net "GND")
		)
	)
)
